# T6G (Grand Teton) — schematic netlist excerpt (pin names and nets, part order shuffled) for the footprints in the layout excerpt that follows; sources: Cadence DE-HDL packaged netlist, KiCad conversion of 04192023_DAF0TMB3IC0_F0TG_MB_C_brd_V02_OCP.brd

PC6575  Q_CAP  2.2UF 10V 10% X6S  pkg C0402  page 363 : A = P0V9_RETIMER_CPU0_VCC2 ; B = GND
C6647  Q_CAP_DIFFBUS  DIFF BUS_0.22UF 6.3V 20% X6S  pkg C0201  page 319 : \1\ = P5E_CPU1_P0_TX_BUF_C_DP<9> ; \2\ = P5E_CPU1_P0_TX_BUF_DP<9>
PR279  Q_RES  5.6 1% CHIP  pkg 0402LF  page 222 : A = SW_PVDDIO_P1_BOOT1 ; B = SW_PVDDIO_P1_BOOT1_R

(kicad_pcb
	(version 20260206)
	(generator "pcbnew")
	(generator_version "10.0")
	(general
		(thickness 1.6)
		(legacy_teardrops no)
	)
	(paper "A4")
	(title_block
		(title "04192023_DAF0TMB3IC0_F0TG_MB_C_brd_V02_OCP.brd")
		(comment 1 "Grand Teton / footprints 2680-2682 of 8354")
	)
	(layers
		(0 "F.Cu" signal "TOP")
		(4 "In1.Cu" signal "GND")
		(6 "In2.Cu" signal "IN1")
		(8 "In3.Cu" signal "GND1")
		(10 "In4.Cu" signal "IN2")
		(12 "In5.Cu" signal "GND2")
		(14 "In6.Cu" signal "IN3")
		(16 "In7.Cu" signal "GND3")
		(18 "In8.Cu" signal "VCC")
		(20 "In9.Cu" signal "VCC1")
		(22 "In10.Cu" signal "GND4")
		(24 "In11.Cu" signal "IN4")
		(26 "In12.Cu" signal "GND5")
		(28 "In13.Cu" signal "IN5")
		(30 "In14.Cu" signal "GND6")
		(32 "In15.Cu" signal "IN6")
		(34 "In16.Cu" signal "GND7")
		(2 "B.Cu" signal "BOTTOM")
		(9 "F.Adhes" user "F.Adhesive")
		(11 "B.Adhes" user "B.Adhesive")
		(13 "F.Paste" user "Package Geometry/Pastemask Top")
		(15 "B.Paste" user "Package Geometry/Pastemask Bottom")
		(5 "F.SilkS" user "Ref Des/Silkscreen Top")
		(7 "B.SilkS" user "Ref Des/Silkscreen Bottom")
		(1 "F.Mask" user "Board Geometry/Soldermask Top")
		(3 "B.Mask" user "Board Geometry/Soldermask Bottom")
		(17 "Dwgs.User" user "User.Drawings")
		(19 "Cmts.User" user "User.Comments")
		(21 "Eco1.User" user "User.Eco1")
		(23 "Eco2.User" user "User.Eco2")
		(25 "Edge.Cuts" user "Board Geometry/Outline")
		(27 "Margin" user)
		(31 "F.CrtYd" user "Package Geometry/Place Bound Top")
		(29 "B.CrtYd" user "Package Geometry/Place Bound Bottom")
		(35 "F.Fab" user "Ref Des/Assembly Top")
		(33 "B.Fab" user "Ref Des/Assembly Bottom")
	)
	(footprint ""
		(layer "F.Cu")
		(at 54.30266 -351.372932 90)
		(property "Reference" "PR279"
			(at 0 0 90)
			(layer "F.SilkS")
			(hide yes)
			(effects
				(font
					(size 1.27 1.27)
				)
			)
		)
		(property "Value" ""
			(at 0 0 90)
			(layer "F.Fab")
			(effects
				(font
					(size 1.27 1.27)
				)
			)
		)
		(duplicate_pad_numbers_are_jumpers no)
		(fp_line
			(start 0.7874 -0.4064)
			(end 0.7874 0.4064)
			(stroke
				(width 0.1524)
				(type default)
			)
			(layer "F.SilkS")
		)
		(fp_line
			(start -0.7874 -0.4064)
			(end 0.7874 -0.4064)
			(stroke
				(width 0.1524)
				(type default)
			)
			(layer "F.SilkS")
		)
		(fp_line
			(start 0.7874 0.4064)
			(end -0.7874 0.4064)
			(stroke
				(width 0.1524)
				(type default)
			)
			(layer "F.SilkS")
		)
		(fp_line
			(start -0.7874 0.4064)
			(end -0.7874 -0.4064)
			(stroke
				(width 0.1524)
				(type default)
			)
			(layer "F.SilkS")
		)
		(fp_line
			(start -0.12065 -0.305054)
			(end -0.12065 -0.2794)
			(stroke
				(width 0.1)
				(type default)
			)
			(layer "F.Fab")
		)
		(fp_line
			(start -0.67945 -0.305054)
			(end -0.12065 -0.305054)
			(stroke
				(width 0.1)
				(type default)
			)
			(layer "F.Fab")
		)
		(fp_line
			(start 0.67945 -0.3048)
			(end 0.67945 0.3048)
			(stroke
				(width 0.1)
				(type default)
			)
			(layer "F.Fab")
		)
		(fp_line
			(start 0.12065 -0.3048)
			(end 0.67945 -0.3048)
			(stroke
				(width 0.1)
				(type default)
			)
			(layer "F.Fab")
		)
		(fp_line
			(start 0.12065 -0.2794)
			(end 0.12065 -0.3048)
			(stroke
				(width 0.1)
				(type default)
			)
			(layer "F.Fab")
		)
		(fp_line
			(start -0.12065 -0.2794)
			(end 0.12065 -0.2794)
			(stroke
				(width 0.1)
				(type default)
			)
			(layer "F.Fab")
		)
		(fp_line
			(start 0.120396 0.2794)
			(end -0.12065 0.2794)
			(stroke
				(width 0.1)
				(type default)
			)
			(layer "F.Fab")
		)
		(fp_line
			(start -0.12065 0.2794)
			(end -0.12065 0.3048)
			(stroke
				(width 0.1)
				(type default)
			)
			(layer "F.Fab")
		)
		(fp_line
			(start 0.67945 0.3048)
			(end 0.120396 0.3048)
			(stroke
				(width 0.1)
				(type default)
			)
			(layer "F.Fab")
		)
		(fp_line
			(start 0.120396 0.3048)
			(end 0.120396 0.2794)
			(stroke
				(width 0.1)
				(type default)
			)
			(layer "F.Fab")
		)
		(fp_line
			(start -0.12065 0.3048)
			(end -0.67945 0.3048)
			(stroke
				(width 0.1)
				(type default)
			)
			(layer "F.Fab")
		)
		(fp_line
			(start -0.67945 0.3048)
			(end -0.67945 -0.305054)
			(stroke
				(width 0.1)
				(type default)
			)
			(layer "F.Fab")
		)
		(pad "1" smd circle
			(at -0.40005 0 90)
			(size 0 0)
			(layers "F.Cu" "F.Mask" "F.Paste")
			(net "SW_PVDDIO_P1_BOOT1")
		)
		(pad "2" smd circle
			(at 0.40005 0 90)
			(size 0 0)
			(layers "F.Cu" "F.Mask" "F.Paste")
			(net "SW_PVDDIO_P1_BOOT1_R")
		)
	)
	(footprint ""
		(layer "F.Cu")
		(at 450.508878 -399.340578 90)
		(property "Reference" "PC6575"
			(at 0 0 90)
			(layer "F.SilkS")
			(hide yes)
			(effects
				(font
					(size 1.27 1.27)
				)
			)
		)
		(property "Value" ""
			(at 0 0 90)
			(layer "F.Fab")
			(effects
				(font
					(size 1.27 1.27)
				)
			)
		)
		(duplicate_pad_numbers_are_jumpers no)
		(fp_line
			(start 0.7874 -0.4064)
			(end 0.7874 -0.192278)
			(stroke
				(width 0.1524)
				(type default)
			)
			(layer "F.SilkS")
		)
		(fp_line
			(start -0.7874 -0.4064)
			(end 0.7874 -0.4064)
			(stroke
				(width 0.1524)
				(type default)
			)
			(layer "F.SilkS")
		)
		(fp_line
			(start 0.455422 0.4064)
			(end -0.7874 0.4064)
			(stroke
				(width 0.1524)
				(type default)
			)
			(layer "F.SilkS")
		)
		(fp_line
			(start -0.7874 0.4064)
			(end -0.7874 -0.4064)
			(stroke
				(width 0.1524)
				(type default)
			)
			(layer "F.SilkS")
		)
		(fp_line
			(start -0.12065 -0.305054)
			(end -0.12065 -0.2794)
			(stroke
				(width 0.1)
				(type default)
			)
			(layer "F.Fab")
		)
		(fp_line
			(start -0.67945 -0.305054)
			(end -0.12065 -0.305054)
			(stroke
				(width 0.1)
				(type default)
			)
			(layer "F.Fab")
		)
		(fp_line
			(start 0.67945 -0.3048)
			(end 0.67945 0.3048)
			(stroke
				(width 0.1)
				(type default)
			)
			(layer "F.Fab")
		)
		(fp_line
			(start 0.12065 -0.3048)
			(end 0.67945 -0.3048)
			(stroke
				(width 0.1)
				(type default)
			)
			(layer "F.Fab")
		)
		(fp_line
			(start 0.12065 -0.2794)
			(end 0.12065 -0.3048)
			(stroke
				(width 0.1)
				(type default)
			)
			(layer "F.Fab")
		)
		(fp_line
			(start -0.12065 -0.2794)
			(end 0.12065 -0.2794)
			(stroke
				(width 0.1)
				(type default)
			)
			(layer "F.Fab")
		)
		(fp_line
			(start 0.120396 0.2794)
			(end -0.12065 0.2794)
			(stroke
				(width 0.1)
				(type default)
			)
			(layer "F.Fab")
		)
		(fp_line
			(start -0.12065 0.2794)
			(end -0.12065 0.3048)
			(stroke
				(width 0.1)
				(type default)
			)
			(layer "F.Fab")
		)
		(fp_line
			(start 0.67945 0.3048)
			(end 0.120396 0.3048)
			(stroke
				(width 0.1)
				(type default)
			)
			(layer "F.Fab")
		)
		(fp_line
			(start 0.120396 0.3048)
			(end 0.120396 0.2794)
			(stroke
				(width 0.1)
				(type default)
			)
			(layer "F.Fab")
		)
		(fp_line
			(start -0.12065 0.3048)
			(end -0.67945 0.3048)
			(stroke
				(width 0.1)
				(type default)
			)
			(layer "F.Fab")
		)
		(fp_line
			(start -0.67945 0.3048)
			(end -0.67945 -0.305054)
			(stroke
				(width 0.1)
				(type default)
			)
			(layer "F.Fab")
		)
		(pad "1" smd circle
			(at -0.40005 0 90)
			(size 0 0)
			(layers "F.Cu" "F.Mask" "F.Paste")
			(net "P0V9_RETIMER_CPU0_VCC2")
		)
		(pad "2" smd circle
			(at 0.40005 0 90)
			(size 0 0)
			(layers "F.Cu" "F.Mask" "F.Paste")
			(net "GND")
		)
	)
	(footprint ""
		(layer "F.Cu")
		(at 76.252324 -408.517344 -90)
		(property "Reference" "C6647"
			(at 0 0 270)
			(layer "F.SilkS")
			(hide yes)
			(effects
				(font
					(size 1.27 1.27)
				)
			)
		)
		(property "Value" ""
			(at 0 0 270)
			(layer "F.Fab")
			(effects
				(font
					(size 1.27 1.27)
				)
			)
		)
		(duplicate_pad_numbers_are_jumpers no)
		(fp_line
			(start -0.299974 0.150114)
			(end -0.299974 -0.150114)
			(stroke
				(width 0.1)
				(type default)
			)
			(layer "F.Fab")
		)
		(fp_line
			(start 0.299974 0.150114)
			(end -0.299974 0.150114)
			(stroke
				(width 0.1)
				(type default)
			)
			(layer "F.Fab")
		)
		(fp_line
			(start -0.299974 -0.150114)
			(end 0.299974 -0.150114)
			(stroke
				(width 0.1)
				(type default)
			)
			(layer "F.Fab")
		)
		(fp_line
			(start 0.299974 -0.150114)
			(end 0.299974 0.150114)
			(stroke
				(width 0.1)
				(type default)
			)
			(layer "F.Fab")
		)
		(pad "1" smd rect
			(at -0.2667 0 270)
			(size 0.3048 0.381)
			(layers "F.Cu" "F.Mask" "F.Paste")
			(net "P5E_CPU1_P0_TX_BUF_C_DP<9>")
		)
		(pad "2" smd rect
			(at 0.2667 0 270)
			(size 0.3048 0.381)
			(layers "F.Cu" "F.Mask" "F.Paste")
			(net "P5E_CPU1_P0_TX_BUF_DP<9>")
		)
	)
)
